# S9S_MB_2U (Grand Teton) — schematic netlist excerpt (pin names and nets, part order shuffled) for the footprints in the layout excerpt that follows; sources: Cadence DE-HDL packaged netlist, KiCad conversion of 03242023_DA0F0TMBIJ0_F0T_Motherboard_J_brd_V01_OCP.brd

PC422  Q_CAP  3300PF 50V 10% X7R  pkg 0402  page 284 : A = SH_PVCCFA_EHV_FIVRA_CPU1_R ; B = VSENSE_PVCCFA_EHV_FIVRA_CPU1_DN
R4178  Q_RES  33.2 1% CHIP  pkg 0402LF  page 170 : A = SMB_LM75_2_3V3AUX_SCL ; B = SMB_LM75_2_3V3AUX_SCL_R1

(kicad_pcb
	(version 20260206)
	(generator "pcbnew")
	(generator_version "10.0")
	(general
		(thickness 1.6)
		(legacy_teardrops no)
	)
	(paper "A4")
	(title_block
		(title "03242023_DA0F0TMBIJ0_F0T_Motherboard_J_brd_V01_OCP.brd")
		(comment 1 "Grand Teton / footprints 530-531 of 6105")
	)
	(layers
		(0 "F.Cu" signal "TOP")
		(4 "In1.Cu" signal "GND")
		(6 "In2.Cu" signal "IN1")
		(8 "In3.Cu" signal "GND1")
		(10 "In4.Cu" signal "IN2")
		(12 "In5.Cu" signal "GND2")
		(14 "In6.Cu" signal "IN3")
		(16 "In7.Cu" signal "GND3")
		(18 "In8.Cu" signal "VCC")
		(20 "In9.Cu" signal "VCC1")
		(22 "In10.Cu" signal "GND4")
		(24 "In11.Cu" signal "IN4")
		(26 "In12.Cu" signal "GND5")
		(28 "In13.Cu" signal "IN5")
		(30 "In14.Cu" signal "GND6")
		(32 "In15.Cu" signal "IN6")
		(34 "In16.Cu" signal "GND7")
		(2 "B.Cu" signal "BOTTOM")
		(9 "F.Adhes" user "F.Adhesive")
		(11 "B.Adhes" user "B.Adhesive")
		(13 "F.Paste" user "Package Geometry/Pastemask Top")
		(15 "B.Paste" user "Package Geometry/Pastemask Bottom")
		(5 "F.SilkS" user "Ref Des/Silkscreen Top")
		(7 "B.SilkS" user "Ref Des/Silkscreen Bottom")
		(1 "F.Mask" user "Board Geometry/Soldermask Top")
		(3 "B.Mask" user "Board Geometry/Soldermask Bottom")
		(17 "Dwgs.User" user "User.Drawings")
		(19 "Cmts.User" user "User.Comments")
		(21 "Eco1.User" user "User.Eco1")
		(23 "Eco2.User" user "User.Eco2")
		(25 "Edge.Cuts" user "Board Geometry/Outline")
		(27 "Margin" user)
		(31 "F.CrtYd" user "Package Geometry/Place Bound Top")
		(29 "B.CrtYd" user "Package Geometry/Place Bound Bottom")
		(35 "F.Fab" user "Ref Des/Assembly Top")
		(33 "B.Fab" user "Ref Des/Assembly Bottom")
	)
	(footprint ""
		(layer "F.Cu")
		(at 105.21188 -423.763948 180)
		(property "Reference" "R4178"
			(at 0 0 180)
			(layer "F.SilkS")
			(hide yes)
			(effects
				(font
					(size 1.27 1.27)
				)
			)
		)
		(property "Value" ""
			(at 0 0 180)
			(layer "F.Fab")
			(effects
				(font
					(size 1.27 1.27)
				)
			)
		)
		(duplicate_pad_numbers_are_jumpers no)
		(fp_line
			(start 0.7874 0.4064)
			(end -0.7874 0.4064)
			(stroke
				(width 0.1524)
				(type default)
			)
			(layer "F.SilkS")
		)
		(fp_line
			(start 0.7874 -0.4064)
			(end 0.7874 0.4064)
			(stroke
				(width 0.1524)
				(type default)
			)
			(layer "F.SilkS")
		)
		(fp_line
			(start -0.7874 0.4064)
			(end -0.7874 -0.4064)
			(stroke
				(width 0.1524)
				(type default)
			)
			(layer "F.SilkS")
		)
		(fp_line
			(start -0.7874 -0.4064)
			(end 0.7874 -0.4064)
			(stroke
				(width 0.1524)
				(type default)
			)
			(layer "F.SilkS")
		)
		(fp_line
			(start 0.67945 0.3048)
			(end 0.120396 0.3048)
			(stroke
				(width 0.1)
				(type default)
			)
			(layer "F.Fab")
		)
		(fp_line
			(start 0.67945 -0.3048)
			(end 0.67945 0.3048)
			(stroke
				(width 0.1)
				(type default)
			)
			(layer "F.Fab")
		)
		(fp_line
			(start 0.12065 -0.2794)
			(end 0.12065 -0.3048)
			(stroke
				(width 0.1)
				(type default)
			)
			(layer "F.Fab")
		)
		(fp_line
			(start 0.12065 -0.3048)
			(end 0.67945 -0.3048)
			(stroke
				(width 0.1)
				(type default)
			)
			(layer "F.Fab")
		)
		(fp_line
			(start 0.120396 0.3048)
			(end 0.120396 0.2794)
			(stroke
				(width 0.1)
				(type default)
			)
			(layer "F.Fab")
		)
		(fp_line
			(start 0.120396 0.2794)
			(end -0.12065 0.2794)
			(stroke
				(width 0.1)
				(type default)
			)
			(layer "F.Fab")
		)
		(fp_line
			(start -0.12065 0.3048)
			(end -0.67945 0.3048)
			(stroke
				(width 0.1)
				(type default)
			)
			(layer "F.Fab")
		)
		(fp_line
			(start -0.12065 0.2794)
			(end -0.12065 0.3048)
			(stroke
				(width 0.1)
				(type default)
			)
			(layer "F.Fab")
		)
		(fp_line
			(start -0.12065 -0.2794)
			(end 0.12065 -0.2794)
			(stroke
				(width 0.1)
				(type default)
			)
			(layer "F.Fab")
		)
		(fp_line
			(start -0.12065 -0.305054)
			(end -0.12065 -0.2794)
			(stroke
				(width 0.1)
				(type default)
			)
			(layer "F.Fab")
		)
		(fp_line
			(start -0.67945 0.3048)
			(end -0.67945 -0.305054)
			(stroke
				(width 0.1)
				(type default)
			)
			(layer "F.Fab")
		)
		(fp_line
			(start -0.67945 -0.305054)
			(end -0.12065 -0.305054)
			(stroke
				(width 0.1)
				(type default)
			)
			(layer "F.Fab")
		)
		(pad "1" smd circle
			(at -0.40005 0 180)
			(size 0 0)
			(layers "F.Cu" "F.Mask" "F.Paste")
			(net "SMB_LM75_2_3V3AUX_SCL")
		)
		(pad "2" smd circle
			(at 0.40005 0 180)
			(size 0 0)
			(layers "F.Cu" "F.Mask" "F.Paste")
			(net "SMB_LM75_2_3V3AUX_SCL_R1")
		)
	)
	(footprint ""
		(layer "F.Cu")
		(at 114.957606 -354.065586)
		(property "Reference" "PC422"
			(at 0 0 0)
			(layer "F.SilkS")
			(hide yes)
			(effects
				(font
					(size 1.27 1.27)
				)
			)
		)
		(property "Value" ""
			(at 0 0 0)
			(layer "F.Fab")
			(effects
				(font
					(size 1.27 1.27)
				)
			)
		)
		(duplicate_pad_numbers_are_jumpers no)
		(fp_line
			(start -0.7874 -0.4064)
			(end 0.7874 -0.4064)
			(stroke
				(width 0.1524)
				(type default)
			)
			(layer "F.SilkS")
		)
		(fp_line
			(start -0.7874 0.4064)
			(end -0.7874 -0.4064)
			(stroke
				(width 0.1524)
				(type default)
			)
			(layer "F.SilkS")
		)
		(fp_line
			(start 0.7874 -0.4064)
			(end 0.7874 0.4064)
			(stroke
				(width 0.1524)
				(type default)
			)
			(layer "F.SilkS")
		)
		(fp_line
			(start 0.7874 0.4064)
			(end -0.7874 0.4064)
			(stroke
				(width 0.1524)
				(type default)
			)
			(layer "F.SilkS")
		)
		(fp_line
			(start -0.67945 -0.305054)
			(end -0.12065 -0.305054)
			(stroke
				(width 0.1)
				(type default)
			)
			(layer "F.Fab")
		)
		(fp_line
			(start -0.67945 0.3048)
			(end -0.67945 -0.305054)
			(stroke
				(width 0.1)
				(type default)
			)
			(layer "F.Fab")
		)
		(fp_line
			(start -0.12065 -0.305054)
			(end -0.12065 -0.2794)
			(stroke
				(width 0.1)
				(type default)
			)
			(layer "F.Fab")
		)
		(fp_line
			(start -0.12065 -0.2794)
			(end 0.12065 -0.2794)
			(stroke
				(width 0.1)
				(type default)
			)
			(layer "F.Fab")
		)
		(fp_line
			(start -0.12065 0.2794)
			(end -0.12065 0.3048)
			(stroke
				(width 0.1)
				(type default)
			)
			(layer "F.Fab")
		)
		(fp_line
			(start -0.12065 0.3048)
			(end -0.67945 0.3048)
			(stroke
				(width 0.1)
				(type default)
			)
			(layer "F.Fab")
		)
		(fp_line
			(start 0.120396 0.2794)
			(end -0.12065 0.2794)
			(stroke
				(width 0.1)
				(type default)
			)
			(layer "F.Fab")
		)
		(fp_line
			(start 0.120396 0.3048)
			(end 0.120396 0.2794)
			(stroke
				(width 0.1)
				(type default)
			)
			(layer "F.Fab")
		)
		(fp_line
			(start 0.12065 -0.3048)
			(end 0.67945 -0.3048)
			(stroke
				(width 0.1)
				(type default)
			)
			(layer "F.Fab")
		)
		(fp_line
			(start 0.12065 -0.2794)
			(end 0.12065 -0.3048)
			(stroke
				(width 0.1)
				(type default)
			)
			(layer "F.Fab")
		)
		(fp_line
			(start 0.67945 -0.3048)
			(end 0.67945 0.3048)
			(stroke
				(width 0.1)
				(type default)
			)
			(layer "F.Fab")
		)
		(fp_line
			(start 0.67945 0.3048)
			(end 0.120396 0.3048)
			(stroke
				(width 0.1)
				(type default)
			)
			(layer "F.Fab")
		)
		(pad "1" smd circle
			(at -0.40005 0)
			(size 0 0)
			(layers "F.Cu" "F.Mask" "F.Paste")
			(net "SH_PVCCFA_EHV_FIVRA_CPU1_R")
		)
		(pad "2" smd circle
			(at 0.40005 0)
			(size 0 0)
			(layers "F.Cu" "F.Mask" "F.Paste")
			(net "VSENSE_PVCCFA_EHV_FIVRA_CPU1_DN")
		)
	)
)
